(kicad_pcb
	(version 20260206)
	(generator "pcbnew")
	(generator_version "10.0")
	(general
		(thickness 1.6)
		(legacy_teardrops no)
	)
	(paper "A4")
	(title_block
		(title "Wiwynn_Tioga_Pass_MB.brd")
		(comment 1 "Tioga Pass / footprints 577-584 of 4770")
	)
	(layers
		(0 "F.Cu" signal "TOP")
		(4 "In1.Cu" signal "L2GND")
		(6 "In2.Cu" signal "L3")
		(8 "In3.Cu" signal "L4GND")
		(10 "In4.Cu" signal "L5")
		(12 "In5.Cu" signal "L6GND")
		(14 "In6.Cu" signal "L7VCC")
		(16 "In7.Cu" signal "L8VCC")
		(18 "In8.Cu" signal "L9GND")
		(20 "In9.Cu" signal "L10")
		(22 "In10.Cu" signal "L11GND")
		(24 "In11.Cu" signal "L12")
		(26 "In12.Cu" signal "L13GND")
		(2 "B.Cu" signal "BOTTOM")
		(9 "F.Adhes" user "F.Adhesive")
		(11 "B.Adhes" user "B.Adhesive")
		(13 "F.Paste" user "Package Geometry/Pastemask Top")
		(15 "B.Paste" user "Package Geometry/Pastemask Bottom")
		(5 "F.SilkS" user "Ref Des/Silkscreen Top")
		(7 "B.SilkS" user "Ref Des/Silkscreen Bottom")
		(1 "F.Mask" user "Board Geometry/Soldermask Top")
		(3 "B.Mask" user "Board Geometry/Soldermask Bottom")
		(17 "Dwgs.User" user "User.Drawings")
		(19 "Cmts.User" user "User.Comments")
		(21 "Eco1.User" user "User.Eco1")
		(23 "Eco2.User" user "User.Eco2")
		(25 "Edge.Cuts" user "Board Geometry/Outline")
		(27 "Margin" user)
		(31 "F.CrtYd" user "Package Geometry/Place Bound Top")
		(29 "B.CrtYd" user "Package Geometry/Place Bound Bottom")
		(35 "F.Fab" user "Ref Des/Assembly Top")
		(33 "B.Fab" user "Ref Des/Assembly Bottom")
	)
	(footprint ""
		(layer "F.Cu")
		(at 175.133 -131.3815 180)
		(property "Reference" "R4B8"
			(at 0 0 180)
			(layer "F.SilkS")
			(hide yes)
			(effects
				(font
					(size 1.27 1.27)
				)
			)
		)
		(property "Value" ""
			(at 0 0 180)
			(layer "F.Fab")
			(effects
				(font
					(size 1.27 1.27)
				)
			)
		)
		(duplicate_pad_numbers_are_jumpers no)
		(fp_poly
			(pts
				(xy -0.2794 -0.1016) (xy 0.2794 -0.1016) (xy 0.2794 0.9906) (xy -0.2794 0.9906)
			)
			(stroke
				(width 0)
				(type default)
			)
			(fill no)
			(layer "F.CrtYd")
		)
		(fp_line
			(start 0.2794 0.9906)
			(end 0.2794 -0.1016)
			(stroke
				(width 0.1)
				(type default)
			)
			(layer "F.Fab")
		)
		(fp_line
			(start 0.2794 -0.1016)
			(end -0.2794 -0.1016)
			(stroke
				(width 0.1)
				(type default)
			)
			(layer "F.Fab")
		)
		(fp_line
			(start -0.2794 0.9906)
			(end 0.2794 0.9906)
			(stroke
				(width 0.1)
				(type default)
			)
			(layer "F.Fab")
		)
		(fp_line
			(start -0.2794 -0.1016)
			(end -0.2794 0.9906)
			(stroke
				(width 0.1)
				(type default)
			)
			(layer "F.Fab")
		)
		(pad "1" smd rect
			(at 0 0 180)
			(size 0.508 0.508)
			(layers "F.Cu" "F.Mask" "F.Paste")
			(net "VR_COMP_RC_PVPP_KLM")
		)
		(pad "2" smd rect
			(at 0 0.889 180)
			(size 0.508 0.508)
			(layers "F.Cu" "F.Mask" "F.Paste")
			(net "VR_FB_PVPP_KLM")
		)
		(zone
			(layer "F.Cu")
			(hatch none 0.5)
			(connect_pads
				(clearance 0)
			)
			(min_thickness 0.25)
			(keepout
				(tracks not_allowed)
				(vias allowed)
				(pads allowed)
				(copperpour not_allowed)
				(footprints allowed)
			)
			(placement
				(enabled no)
				(sheetname "")
			)
			(fill
				(thermal_gap 0.5)
				(thermal_bridge_width 0.5)
				(island_removal_mode 0)
			)
			(polygon
				(pts
					(xy 175.387 -132.0165) (xy 174.879 -132.0165) (xy 174.879 -131.6355) (xy 175.387 -131.6355)
				)
			)
		)
		(zone
			(layer "F.Cu")
			(hatch none 0.5)
			(connect_pads
				(clearance 0)
			)
			(min_thickness 0.25)
			(keepout
				(tracks allowed)
				(vias not_allowed)
				(pads allowed)
				(copperpour not_allowed)
				(footprints allowed)
			)
			(placement
				(enabled no)
				(sheetname "")
			)
			(fill
				(thermal_gap 0.5)
				(thermal_bridge_width 0.5)
				(island_removal_mode 0)
			)
			(polygon
				(pts
					(xy 175.387 -131.6355) (xy 174.879 -131.6355) (xy 174.879 -132.0165) (xy 175.387 -132.0165)
				)
			)
		)
	)
	(footprint ""
		(layer "F.Cu")
		(at 406.654 -93.280992 90)
		(property "Reference" "C8C6"
			(at 0 0 90)
			(layer "F.SilkS")
			(hide yes)
			(effects
				(font
					(size 1.27 1.27)
				)
			)
		)
		(property "Value" ""
			(at 0 0 90)
			(layer "F.Fab")
			(effects
				(font
					(size 1.27 1.27)
				)
			)
		)
		(duplicate_pad_numbers_are_jumpers no)
		(fp_poly
			(pts
				(xy -0.4953 -0.2032) (xy 0.4953 -0.2032) (xy 0.4953 1.6002) (xy -0.4953 1.6002)
			)
			(stroke
				(width 0)
				(type default)
			)
			(fill no)
			(layer "F.CrtYd")
		)
		(fp_line
			(start 0.4953 -0.2032)
			(end 0.4953 1.6002)
			(stroke
				(width 0.1)
				(type default)
			)
			(layer "F.Fab")
		)
		(fp_line
			(start -0.4953 -0.2032)
			(end 0.4953 -0.2032)
			(stroke
				(width 0.1)
				(type default)
			)
			(layer "F.Fab")
		)
		(fp_line
			(start 0.4953 1.6002)
			(end -0.4953 1.6002)
			(stroke
				(width 0.1)
				(type default)
			)
			(layer "F.Fab")
		)
		(fp_line
			(start -0.4953 1.6002)
			(end -0.4953 -0.2032)
			(stroke
				(width 0.1)
				(type default)
			)
			(layer "F.Fab")
		)
		(pad "1" smd rect
			(at 0 0 90)
			(size 0.762 0.889)
			(layers "F.Cu" "F.Mask" "F.Paste")
			(net "P3V3_STBY")
		)
		(pad "2" smd rect
			(at 0 1.397 90)
			(size 0.762 0.889)
			(layers "F.Cu" "F.Mask" "F.Paste")
			(net "GND")
		)
		(zone
			(layer "F.Cu")
			(hatch none 0.5)
			(connect_pads
				(clearance 0)
			)
			(min_thickness 0.25)
			(keepout
				(tracks not_allowed)
				(vias allowed)
				(pads allowed)
				(copperpour not_allowed)
				(footprints allowed)
			)
			(placement
				(enabled no)
				(sheetname "")
			)
			(fill
				(thermal_gap 0.5)
				(thermal_bridge_width 0.5)
				(island_removal_mode 0)
			)
			(polygon
				(pts
					(xy 407.0985 -92.899992) (xy 407.0985 -93.661992) (xy 407.6065 -93.661992) (xy 407.6065 -92.899992)
				)
			)
		)
	)
	(footprint ""
		(layer "F.Cu")
		(at 164.465 -74.803)
		(property "Reference" "C4D23"
			(at 0 0 0)
			(layer "F.SilkS")
			(hide yes)
			(effects
				(font
					(size 1.27 1.27)
				)
			)
		)
		(property "Value" ""
			(at 0 0 0)
			(layer "F.Fab")
			(effects
				(font
					(size 1.27 1.27)
				)
			)
		)
		(duplicate_pad_numbers_are_jumpers no)
		(fp_poly
			(pts
				(xy 0.3048 -0.1016) (xy 0.3048 0.9906) (xy -0.3048 0.9906) (xy -0.3048 -0.1016)
			)
			(stroke
				(width 0)
				(type default)
			)
			(fill no)
			(layer "F.CrtYd")
		)
		(fp_line
			(start -0.3048 -0.1016)
			(end -0.3048 0.9906)
			(stroke
				(width 0.1)
				(type default)
			)
			(layer "F.Fab")
		)
		(fp_line
			(start -0.3048 0.9906)
			(end 0.3048 0.9906)
			(stroke
				(width 0.1)
				(type default)
			)
			(layer "F.Fab")
		)
		(fp_line
			(start 0.3048 -0.1016)
			(end -0.3048 -0.1016)
			(stroke
				(width 0.1)
				(type default)
			)
			(layer "F.Fab")
		)
		(fp_line
			(start 0.3048 0.9906)
			(end 0.3048 -0.1016)
			(stroke
				(width 0.1)
				(type default)
			)
			(layer "F.Fab")
		)
		(pad "1" smd rect
			(at 0 0)
			(size 0.508 0.508)
			(layers "F.Cu" "F.Mask" "F.Paste")
			(net "P3V3_DB1200_A")
		)
		(pad "2" smd rect
			(at 0 0.889)
			(size 0.508 0.508)
			(layers "F.Cu" "F.Mask" "F.Paste")
			(net "GND")
		)
		(zone
			(layer "F.Cu")
			(hatch none 0.5)
			(connect_pads
				(clearance 0)
			)
			(min_thickness 0.25)
			(keepout
				(tracks allowed)
				(vias not_allowed)
				(pads allowed)
				(copperpour not_allowed)
				(footprints allowed)
			)
			(placement
				(enabled no)
				(sheetname "")
			)
			(fill
				(thermal_gap 0.5)
				(thermal_bridge_width 0.5)
				(island_removal_mode 0)
			)
			(polygon
				(pts
					(xy 164.211 -74.549) (xy 164.719 -74.549) (xy 164.719 -74.168) (xy 164.211 -74.168)
				)
			)
		)
		(zone
			(layer "F.Cu")
			(hatch none 0.5)
			(connect_pads
				(clearance 0)
			)
			(min_thickness 0.25)
			(keepout
				(tracks not_allowed)
				(vias allowed)
				(pads allowed)
				(copperpour not_allowed)
				(footprints allowed)
			)
			(placement
				(enabled no)
				(sheetname "")
			)
			(fill
				(thermal_gap 0.5)
				(thermal_bridge_width 0.5)
				(island_removal_mode 0)
			)
			(polygon
				(pts
					(xy 164.211 -74.168) (xy 164.719 -74.168) (xy 164.719 -74.549) (xy 164.211 -74.549)
				)
			)
		)
	)
	(footprint ""
		(layer "F.Cu")
		(at 104.40924 -77.636116)
		(property "Reference" "C2D28"
			(at 0 0 0)
			(layer "F.SilkS")
			(hide yes)
			(effects
				(font
					(size 1.27 1.27)
				)
			)
		)
		(property "Value" ""
			(at 0 0 0)
			(layer "F.Fab")
			(effects
				(font
					(size 1.27 1.27)
				)
			)
		)
		(duplicate_pad_numbers_are_jumpers no)
		(fp_poly
			(pts
				(xy -0.4953 -0.2032) (xy 0.4953 -0.2032) (xy 0.4953 1.6002) (xy -0.4953 1.6002)
			)
			(stroke
				(width 0)
				(type default)
			)
			(fill no)
			(layer "F.CrtYd")
		)
		(fp_line
			(start -0.4953 -0.2032)
			(end 0.4953 -0.2032)
			(stroke
				(width 0.1)
				(type default)
			)
			(layer "F.Fab")
		)
		(fp_line
			(start -0.4953 1.6002)
			(end -0.4953 -0.2032)
			(stroke
				(width 0.1)
				(type default)
			)
			(layer "F.Fab")
		)
		(fp_line
			(start 0.4953 -0.2032)
			(end 0.4953 1.6002)
			(stroke
				(width 0.1)
				(type default)
			)
			(layer "F.Fab")
		)
		(fp_line
			(start 0.4953 1.6002)
			(end -0.4953 1.6002)
			(stroke
				(width 0.1)
				(type default)
			)
			(layer "F.Fab")
		)
		(pad "1" smd rect
			(at 0 0)
			(size 0.762 0.889)
			(layers "F.Cu" "F.Mask" "F.Paste")
			(net "PVCCMCP_CPU1")
		)
		(pad "2" smd rect
			(at 0 1.397)
			(size 0.762 0.889)
			(layers "F.Cu" "F.Mask" "F.Paste")
			(net "GND")
		)
		(zone
			(layer "F.Cu")
			(hatch none 0.5)
			(connect_pads
				(clearance 0)
			)
			(min_thickness 0.25)
			(keepout
				(tracks not_allowed)
				(vias allowed)
				(pads allowed)
				(copperpour not_allowed)
				(footprints allowed)
			)
			(placement
				(enabled no)
				(sheetname "")
			)
			(fill
				(thermal_gap 0.5)
				(thermal_bridge_width 0.5)
				(island_removal_mode 0)
			)
			(polygon
				(pts
					(xy 104.02824 -77.191616) (xy 104.79024 -77.191616) (xy 104.79024 -76.683616) (xy 104.02824 -76.683616)
				)
			)
		)
	)
	(footprint ""
		(layer "F.Cu")
		(at 347.988636 -141.454378 -90)
		(property "Reference" "C7A20"
			(at 0 0 270)
			(layer "F.SilkS")
			(hide yes)
			(effects
				(font
					(size 1.27 1.27)
				)
			)
		)
		(property "Value" ""
			(at 0 0 270)
			(layer "F.Fab")
			(effects
				(font
					(size 1.27 1.27)
				)
			)
		)
		(duplicate_pad_numbers_are_jumpers no)
		(fp_poly
			(pts
				(xy 0.3048 -0.1016) (xy 0.3048 0.9906) (xy -0.3048 0.9906) (xy -0.3048 -0.1016)
			)
			(stroke
				(width 0)
				(type default)
			)
			(fill no)
			(layer "F.CrtYd")
		)
		(fp_line
			(start -0.3048 0.9906)
			(end 0.3048 0.9906)
			(stroke
				(width 0.1)
				(type default)
			)
			(layer "F.Fab")
		)
		(fp_line
			(start 0.3048 0.9906)
			(end 0.3048 -0.1016)
			(stroke
				(width 0.1)
				(type default)
			)
			(layer "F.Fab")
		)
		(fp_line
			(start -0.3048 -0.1016)
			(end -0.3048 0.9906)
			(stroke
				(width 0.1)
				(type default)
			)
			(layer "F.Fab")
		)
		(fp_line
			(start 0.3048 -0.1016)
			(end -0.3048 -0.1016)
			(stroke
				(width 0.1)
				(type default)
			)
			(layer "F.Fab")
		)
		(pad "1" smd rect
			(at 0 0 270)
			(size 0.508 0.508)
			(layers "F.Cu" "F.Mask" "F.Paste")
			(net "VR_FET_SW_P12V_STBY_PVDDQ_DEF")
		)
		(pad "2" smd rect
			(at 0 0.889 270)
			(size 0.508 0.508)
			(layers "F.Cu" "F.Mask" "F.Paste")
			(net "GND")
		)
		(zone
			(layer "F.Cu")
			(hatch none 0.5)
			(connect_pads
				(clearance 0)
			)
			(min_thickness 0.25)
			(keepout
				(tracks not_allowed)
				(vias allowed)
				(pads allowed)
				(copperpour not_allowed)
				(footprints allowed)
			)
			(placement
				(enabled no)
				(sheetname "")
			)
			(fill
				(thermal_gap 0.5)
				(thermal_bridge_width 0.5)
				(island_removal_mode 0)
			)
			(polygon
				(pts
					(xy 347.353636 -141.708378) (xy 347.353636 -141.200378) (xy 347.734636 -141.200378) (xy 347.734636 -141.708378)
				)
			)
		)
		(zone
			(layer "F.Cu")
			(hatch none 0.5)
			(connect_pads
				(clearance 0)
			)
			(min_thickness 0.25)
			(keepout
				(tracks allowed)
				(vias not_allowed)
				(pads allowed)
				(copperpour not_allowed)
				(footprints allowed)
			)
			(placement
				(enabled no)
				(sheetname "")
			)
			(fill
				(thermal_gap 0.5)
				(thermal_bridge_width 0.5)
				(island_removal_mode 0)
			)
			(polygon
				(pts
					(xy 347.734636 -141.708378) (xy 347.734636 -141.200378) (xy 347.353636 -141.200378) (xy 347.353636 -141.708378)
				)
			)
		)
	)
	(footprint ""
		(layer "F.Cu")
		(at 445.91732 -24.47798)
		(property "Reference" "C25W14"
			(at -0.8382 -0.67818 0)
			(unlocked yes)
			(layer "F.SilkS")
			(effects
				(font
					(size 0.4064 0.254)
					(thickness 0.1524)
				)
				(justify left)
			)
		)
		(property "Value" ""
			(at 0 0 0)
			(layer "F.Fab")
			(effects
				(font
					(size 1.27 1.27)
				)
			)
		)
		(duplicate_pad_numbers_are_jumpers no)
		(fp_poly
			(pts
				(xy 0.3048 -0.1016) (xy 0.3048 0.9906) (xy -0.3048 0.9906) (xy -0.3048 -0.1016)
			)
			(stroke
				(width 0)
				(type default)
			)
			(fill no)
			(layer "F.CrtYd")
		)
		(fp_line
			(start -0.3048 -0.1016)
			(end -0.3048 0.9906)
			(stroke
				(width 0.1)
				(type default)
			)
			(layer "F.Fab")
		)
		(fp_line
			(start -0.3048 0.9906)
			(end 0.3048 0.9906)
			(stroke
				(width 0.1)
				(type default)
			)
			(layer "F.Fab")
		)
		(fp_line
			(start 0.3048 -0.1016)
			(end -0.3048 -0.1016)
			(stroke
				(width 0.1)
				(type default)
			)
			(layer "F.Fab")
		)
		(fp_line
			(start 0.3048 0.9906)
			(end 0.3048 -0.1016)
			(stroke
				(width 0.1)
				(type default)
			)
			(layer "F.Fab")
		)
		(pad "1" smd rect
			(at 0 0)
			(size 0.508 0.508)
			(layers "F.Cu" "F.Mask" "F.Paste")
			(net "P2V5_AUX_BMC")
		)
		(pad "2" smd rect
			(at 0 0.889)
			(size 0.508 0.508)
			(layers "F.Cu" "F.Mask" "F.Paste")
			(net "GND")
		)
		(zone
			(layer "F.Cu")
			(hatch none 0.5)
			(connect_pads
				(clearance 0)
			)
			(min_thickness 0.25)
			(keepout
				(tracks allowed)
				(vias not_allowed)
				(pads allowed)
				(copperpour not_allowed)
				(footprints allowed)
			)
			(placement
				(enabled no)
				(sheetname "")
			)
			(fill
				(thermal_gap 0.5)
				(thermal_bridge_width 0.5)
				(island_removal_mode 0)
			)
			(polygon
				(pts
					(xy 445.66332 -24.22398) (xy 446.17132 -24.22398) (xy 446.17132 -23.84298) (xy 445.66332 -23.84298)
				)
			)
		)
		(zone
			(layer "F.Cu")
			(hatch none 0.5)
			(connect_pads
				(clearance 0)
			)
			(min_thickness 0.25)
			(keepout
				(tracks not_allowed)
				(vias allowed)
				(pads allowed)
				(copperpour not_allowed)
				(footprints allowed)
			)
			(placement
				(enabled no)
				(sheetname "")
			)
			(fill
				(thermal_gap 0.5)
				(thermal_bridge_width 0.5)
				(island_removal_mode 0)
			)
			(polygon
				(pts
					(xy 445.66332 -23.84298) (xy 446.17132 -23.84298) (xy 446.17132 -24.22398) (xy 445.66332 -24.22398)
				)
			)
		)
	)
	(footprint ""
		(layer "F.Cu")
		(at 417.398454 -105.34777 180)
		(property "Reference" "C9W8"
			(at -0.8382 -0.67818 180)
			(unlocked yes)
			(layer "F.SilkS")
			(effects
				(font
					(size 0.4064 0.254)
					(thickness 0.1524)
				)
				(justify left)
			)
		)
		(property "Value" ""
			(at 0 0 180)
			(layer "F.Fab")
			(effects
				(font
					(size 1.27 1.27)
				)
			)
		)
		(duplicate_pad_numbers_are_jumpers no)
		(fp_poly
			(pts
				(xy 0.3048 -0.1016) (xy 0.3048 0.9906) (xy -0.3048 0.9906) (xy -0.3048 -0.1016)
			)
			(stroke
				(width 0)
				(type default)
			)
			(fill no)
			(layer "F.CrtYd")
		)
		(fp_line
			(start 0.3048 0.9906)
			(end 0.3048 -0.1016)
			(stroke
				(width 0.1)
				(type default)
			)
			(layer "F.Fab")
		)
		(fp_line
			(start 0.3048 -0.1016)
			(end -0.3048 -0.1016)
			(stroke
				(width 0.1)
				(type default)
			)
			(layer "F.Fab")
		)
		(fp_line
			(start -0.3048 0.9906)
			(end 0.3048 0.9906)
			(stroke
				(width 0.1)
				(type default)
			)
			(layer "F.Fab")
		)
		(fp_line
			(start -0.3048 -0.1016)
			(end -0.3048 0.9906)
			(stroke
				(width 0.1)
				(type default)
			)
			(layer "F.Fab")
		)
		(pad "1" smd rect
			(at 0 0 180)
			(size 0.508 0.508)
			(layers "F.Cu" "F.Mask" "F.Paste")
			(net "PVCCIO_CPU0")
		)
		(pad "2" smd rect
			(at 0 0.889 180)
			(size 0.508 0.508)
			(layers "F.Cu" "F.Mask" "F.Paste")
			(net "GND")
		)
		(zone
			(layer "F.Cu")
			(hatch none 0.5)
			(connect_pads
				(clearance 0)
			)
			(min_thickness 0.25)
			(keepout
				(tracks not_allowed)
				(vias allowed)
				(pads allowed)
				(copperpour not_allowed)
				(footprints allowed)
			)
			(placement
				(enabled no)
				(sheetname "")
			)
			(fill
				(thermal_gap 0.5)
				(thermal_bridge_width 0.5)
				(island_removal_mode 0)
			)
			(polygon
				(pts
					(xy 417.652454 -105.98277) (xy 417.144454 -105.98277) (xy 417.144454 -105.60177) (xy 417.652454 -105.60177)
				)
			)
		)
		(zone
			(layer "F.Cu")
			(hatch none 0.5)
			(connect_pads
				(clearance 0)
			)
			(min_thickness 0.25)
			(keepout
				(tracks allowed)
				(vias not_allowed)
				(pads allowed)
				(copperpour not_allowed)
				(footprints allowed)
			)
			(placement
				(enabled no)
				(sheetname "")
			)
			(fill
				(thermal_gap 0.5)
				(thermal_bridge_width 0.5)
				(island_removal_mode 0)
			)
			(polygon
				(pts
					(xy 417.652454 -105.60177) (xy 417.144454 -105.60177) (xy 417.144454 -105.98277) (xy 417.652454 -105.98277)
				)
			)
		)
	)
	(footprint ""
		(layer "F.Cu")
		(at 394.589 -85.0265 180)
		(property "Reference" "R2U11"
			(at 0 0 180)
			(layer "F.SilkS")
			(hide yes)
			(effects
				(font
					(size 1.27 1.27)
				)
			)
		)
		(property "Value" ""
			(at 0 0 180)
			(layer "F.Fab")
			(effects
				(font
					(size 1.27 1.27)
				)
			)
		)
		(duplicate_pad_numbers_are_jumpers no)
		(fp_poly
			(pts
				(xy -0.2794 -0.1016) (xy 0.2794 -0.1016) (xy 0.2794 0.9906) (xy -0.2794 0.9906)
			)
			(stroke
				(width 0)
				(type default)
			)
			(fill no)
			(layer "F.CrtYd")
		)
		(fp_line
			(start 0.2794 0.9906)
			(end 0.2794 -0.1016)
			(stroke
				(width 0.1)
				(type default)
			)
			(layer "F.Fab")
		)
		(fp_line
			(start 0.2794 -0.1016)
			(end -0.2794 -0.1016)
			(stroke
				(width 0.1)
				(type default)
			)
			(layer "F.Fab")
		)
		(fp_line
			(start -0.2794 0.9906)
			(end 0.2794 0.9906)
			(stroke
				(width 0.1)
				(type default)
			)
			(layer "F.Fab")
		)
		(fp_line
			(start -0.2794 -0.1016)
			(end -0.2794 0.9906)
			(stroke
				(width 0.1)
				(type default)
			)
			(layer "F.Fab")
		)
		(pad "1" smd rect
			(at 0 0 180)
			(size 0.508 0.508)
			(layers "F.Cu" "F.Mask" "F.Paste")
			(net "P3V3_STBY")
		)
		(pad "2" smd rect
			(at 0 0.889 180)
			(size 0.508 0.508)
			(layers "F.Cu" "F.Mask" "F.Paste")
			(net "SMB_LAN_STBY_LVC3_SDA")
		)
		(zone
			(layer "F.Cu")
			(hatch none 0.5)
			(connect_pads
				(clearance 0)
			)
			(min_thickness 0.25)
			(keepout
				(tracks not_allowed)
				(vias allowed)
				(pads allowed)
				(copperpour not_allowed)
				(footprints allowed)
			)
			(placement
				(enabled no)
				(sheetname "")
			)
			(fill
				(thermal_gap 0.5)
				(thermal_bridge_width 0.5)
				(island_removal_mode 0)
			)
			(polygon
				(pts
					(xy 394.843 -85.6615) (xy 394.335 -85.6615) (xy 394.335 -85.2805) (xy 394.843 -85.2805)
				)
			)
		)
		(zone
			(layer "F.Cu")
			(hatch none 0.5)
			(connect_pads
				(clearance 0)
			)
			(min_thickness 0.25)
			(keepout
				(tracks allowed)
				(vias not_allowed)
				(pads allowed)
				(copperpour not_allowed)
				(footprints allowed)
			)
			(placement
				(enabled no)
				(sheetname "")
			)
			(fill
				(thermal_gap 0.5)
				(thermal_bridge_width 0.5)
				(island_removal_mode 0)
			)
			(polygon
				(pts
					(xy 394.843 -85.2805) (xy 394.335 -85.2805) (xy 394.335 -85.6615) (xy 394.843 -85.6615)
				)
			)
		)
	)
)
